(kicad_pcb
	(version 20260206)
	(generator "pcbnew")
	(generator_version "10.0")
	(general
		(thickness 1.6)
		(legacy_teardrops no)
	)
	(paper "A4")
	(title_block
		(title "03242023_DA0F0TMBIJ0_F0T_Motherboard_J_brd_V01_OCP.brd")
		(comment 1 "Grand Teton / footprints 3794-3799 of 6105")
	)
	(layers
		(0 "F.Cu" signal "TOP")
		(4 "In1.Cu" signal "GND")
		(6 "In2.Cu" signal "IN1")
		(8 "In3.Cu" signal "GND1")
		(10 "In4.Cu" signal "IN2")
		(12 "In5.Cu" signal "GND2")
		(14 "In6.Cu" signal "IN3")
		(16 "In7.Cu" signal "GND3")
		(18 "In8.Cu" signal "VCC")
		(20 "In9.Cu" signal "VCC1")
		(22 "In10.Cu" signal "GND4")
		(24 "In11.Cu" signal "IN4")
		(26 "In12.Cu" signal "GND5")
		(28 "In13.Cu" signal "IN5")
		(30 "In14.Cu" signal "GND6")
		(32 "In15.Cu" signal "IN6")
		(34 "In16.Cu" signal "GND7")
		(2 "B.Cu" signal "BOTTOM")
		(9 "F.Adhes" user "F.Adhesive")
		(11 "B.Adhes" user "B.Adhesive")
		(13 "F.Paste" user "Package Geometry/Pastemask Top")
		(15 "B.Paste" user "Package Geometry/Pastemask Bottom")
		(5 "F.SilkS" user "Ref Des/Silkscreen Top")
		(7 "B.SilkS" user "Ref Des/Silkscreen Bottom")
		(1 "F.Mask" user "Board Geometry/Soldermask Top")
		(3 "B.Mask" user "Board Geometry/Soldermask Bottom")
		(17 "Dwgs.User" user "User.Drawings")
		(19 "Cmts.User" user "User.Comments")
		(21 "Eco1.User" user "User.Eco1")
		(23 "Eco2.User" user "User.Eco2")
		(25 "Edge.Cuts" user "Board Geometry/Outline")
		(27 "Margin" user)
		(31 "F.CrtYd" user "Package Geometry/Place Bound Top")
		(29 "B.CrtYd" user "Package Geometry/Place Bound Bottom")
		(35 "F.Fab" user "Ref Des/Assembly Top")
		(33 "B.Fab" user "Ref Des/Assembly Bottom")
	)
	(footprint ""
		(layer "F.Cu")
		(at 275.773134 -17.678908 180)
		(property "Reference" "C1822"
			(at 0 0 180)
			(layer "F.SilkS")
			(hide yes)
			(effects
				(font
					(size 1.27 1.27)
				)
			)
		)
		(property "Value" ""
			(at 0 0 180)
			(layer "F.Fab")
			(effects
				(font
					(size 1.27 1.27)
				)
			)
		)
		(duplicate_pad_numbers_are_jumpers no)
		(fp_line
			(start 0.7874 0.4064)
			(end -0.7874 0.4064)
			(stroke
				(width 0.1524)
				(type default)
			)
			(layer "F.SilkS")
		)
		(fp_line
			(start 0.7874 -0.4064)
			(end 0.7874 0.4064)
			(stroke
				(width 0.1524)
				(type default)
			)
			(layer "F.SilkS")
		)
		(fp_line
			(start -0.7874 0.4064)
			(end -0.7874 -0.4064)
			(stroke
				(width 0.1524)
				(type default)
			)
			(layer "F.SilkS")
		)
		(fp_line
			(start -0.7874 -0.4064)
			(end 0.7874 -0.4064)
			(stroke
				(width 0.1524)
				(type default)
			)
			(layer "F.SilkS")
		)
		(fp_line
			(start 0.67945 0.3048)
			(end 0.120396 0.3048)
			(stroke
				(width 0.1)
				(type default)
			)
			(layer "F.Fab")
		)
		(fp_line
			(start 0.67945 -0.3048)
			(end 0.67945 0.3048)
			(stroke
				(width 0.1)
				(type default)
			)
			(layer "F.Fab")
		)
		(fp_line
			(start 0.12065 -0.2794)
			(end 0.12065 -0.3048)
			(stroke
				(width 0.1)
				(type default)
			)
			(layer "F.Fab")
		)
		(fp_line
			(start 0.12065 -0.3048)
			(end 0.67945 -0.3048)
			(stroke
				(width 0.1)
				(type default)
			)
			(layer "F.Fab")
		)
		(fp_line
			(start 0.120396 0.3048)
			(end 0.120396 0.2794)
			(stroke
				(width 0.1)
				(type default)
			)
			(layer "F.Fab")
		)
		(fp_line
			(start 0.120396 0.2794)
			(end -0.12065 0.2794)
			(stroke
				(width 0.1)
				(type default)
			)
			(layer "F.Fab")
		)
		(fp_line
			(start -0.12065 0.3048)
			(end -0.67945 0.3048)
			(stroke
				(width 0.1)
				(type default)
			)
			(layer "F.Fab")
		)
		(fp_line
			(start -0.12065 0.2794)
			(end -0.12065 0.3048)
			(stroke
				(width 0.1)
				(type default)
			)
			(layer "F.Fab")
		)
		(fp_line
			(start -0.12065 -0.2794)
			(end 0.12065 -0.2794)
			(stroke
				(width 0.1)
				(type default)
			)
			(layer "F.Fab")
		)
		(fp_line
			(start -0.12065 -0.305054)
			(end -0.12065 -0.2794)
			(stroke
				(width 0.1)
				(type default)
			)
			(layer "F.Fab")
		)
		(fp_line
			(start -0.67945 0.3048)
			(end -0.67945 -0.305054)
			(stroke
				(width 0.1)
				(type default)
			)
			(layer "F.Fab")
		)
		(fp_line
			(start -0.67945 -0.305054)
			(end -0.12065 -0.305054)
			(stroke
				(width 0.1)
				(type default)
			)
			(layer "F.Fab")
		)
		(pad "1" smd circle
			(at -0.40005 0 180)
			(size 0 0)
			(layers "F.Cu" "F.Mask" "F.Paste")
			(net "P3V3_AUX")
		)
		(pad "2" smd circle
			(at 0.40005 0 180)
			(size 0 0)
			(layers "F.Cu" "F.Mask" "F.Paste")
			(net "GND")
		)
	)
	(footprint ""
		(layer "F.Cu")
		(at 461.463136 -385.742434 90)
		(property "Reference" "PC1898"
			(at 0 0 90)
			(layer "F.SilkS")
			(hide yes)
			(effects
				(font
					(size 1.27 1.27)
				)
			)
		)
		(property "Value" ""
			(at 0 0 90)
			(layer "F.Fab")
			(effects
				(font
					(size 1.27 1.27)
				)
			)
		)
		(duplicate_pad_numbers_are_jumpers no)
		(fp_line
			(start 1.524 -0.762)
			(end 1.524 0.762)
			(stroke
				(width 0.1524)
				(type default)
			)
			(layer "F.SilkS")
		)
		(fp_line
			(start -1.524 -0.762)
			(end 1.524 -0.762)
			(stroke
				(width 0.1524)
				(type default)
			)
			(layer "F.SilkS")
		)
		(fp_line
			(start 1.524 0.762)
			(end -1.524 0.762)
			(stroke
				(width 0.1524)
				(type default)
			)
			(layer "F.SilkS")
		)
		(fp_line
			(start -1.524 0.762)
			(end -1.524 -0.762)
			(stroke
				(width 0.1524)
				(type default)
			)
			(layer "F.SilkS")
		)
		(fp_line
			(start 1.1049 -0.724916)
			(end -1.1049 -0.724916)
			(stroke
				(width 0.1)
				(type default)
			)
			(layer "F.Fab")
		)
		(fp_line
			(start -1.1049 -0.724916)
			(end -1.1049 0.724916)
			(stroke
				(width 0.1)
				(type default)
			)
			(layer "F.Fab")
		)
		(fp_line
			(start 1.1049 0.724916)
			(end 1.1049 -0.724916)
			(stroke
				(width 0.1)
				(type default)
			)
			(layer "F.Fab")
		)
		(fp_line
			(start -1.1049 0.724916)
			(end 1.1049 0.724916)
			(stroke
				(width 0.1)
				(type default)
			)
			(layer "F.Fab")
		)
		(pad "1" smd rect
			(at -0.889 0 270)
			(size 1.016 1.27)
			(layers "F.Cu" "F.Mask" "F.Paste")
			(net "SW_P5V_AUX_FLT")
		)
		(pad "2" smd rect
			(at 0.889 0 270)
			(size 1.016 1.27)
			(layers "F.Cu" "F.Mask" "F.Paste")
			(net "GND")
		)
	)
	(footprint ""
		(layer "F.Cu")
		(at 305.629818 -420.23919 90)
		(property "Reference" "R4268"
			(at 0 0 90)
			(layer "F.SilkS")
			(hide yes)
			(effects
				(font
					(size 1.27 1.27)
				)
			)
		)
		(property "Value" ""
			(at 0 0 90)
			(layer "F.Fab")
			(effects
				(font
					(size 1.27 1.27)
				)
			)
		)
		(duplicate_pad_numbers_are_jumpers no)
		(fp_line
			(start 0.7874 -0.4064)
			(end 0.7874 0.4064)
			(stroke
				(width 0.1524)
				(type default)
			)
			(layer "F.SilkS")
		)
		(fp_line
			(start -0.7874 -0.4064)
			(end 0.7874 -0.4064)
			(stroke
				(width 0.1524)
				(type default)
			)
			(layer "F.SilkS")
		)
		(fp_line
			(start 0.7874 0.4064)
			(end -0.7874 0.4064)
			(stroke
				(width 0.1524)
				(type default)
			)
			(layer "F.SilkS")
		)
		(fp_line
			(start -0.7874 0.4064)
			(end -0.7874 -0.4064)
			(stroke
				(width 0.1524)
				(type default)
			)
			(layer "F.SilkS")
		)
		(fp_line
			(start -0.12065 -0.305054)
			(end -0.12065 -0.2794)
			(stroke
				(width 0.1)
				(type default)
			)
			(layer "F.Fab")
		)
		(fp_line
			(start -0.67945 -0.305054)
			(end -0.12065 -0.305054)
			(stroke
				(width 0.1)
				(type default)
			)
			(layer "F.Fab")
		)
		(fp_line
			(start 0.67945 -0.3048)
			(end 0.67945 0.3048)
			(stroke
				(width 0.1)
				(type default)
			)
			(layer "F.Fab")
		)
		(fp_line
			(start 0.12065 -0.3048)
			(end 0.67945 -0.3048)
			(stroke
				(width 0.1)
				(type default)
			)
			(layer "F.Fab")
		)
		(fp_line
			(start 0.12065 -0.2794)
			(end 0.12065 -0.3048)
			(stroke
				(width 0.1)
				(type default)
			)
			(layer "F.Fab")
		)
		(fp_line
			(start -0.12065 -0.2794)
			(end 0.12065 -0.2794)
			(stroke
				(width 0.1)
				(type default)
			)
			(layer "F.Fab")
		)
		(fp_line
			(start 0.120396 0.2794)
			(end -0.12065 0.2794)
			(stroke
				(width 0.1)
				(type default)
			)
			(layer "F.Fab")
		)
		(fp_line
			(start -0.12065 0.2794)
			(end -0.12065 0.3048)
			(stroke
				(width 0.1)
				(type default)
			)
			(layer "F.Fab")
		)
		(fp_line
			(start 0.67945 0.3048)
			(end 0.120396 0.3048)
			(stroke
				(width 0.1)
				(type default)
			)
			(layer "F.Fab")
		)
		(fp_line
			(start 0.120396 0.3048)
			(end 0.120396 0.2794)
			(stroke
				(width 0.1)
				(type default)
			)
			(layer "F.Fab")
		)
		(fp_line
			(start -0.12065 0.3048)
			(end -0.67945 0.3048)
			(stroke
				(width 0.1)
				(type default)
			)
			(layer "F.Fab")
		)
		(fp_line
			(start -0.67945 0.3048)
			(end -0.67945 -0.305054)
			(stroke
				(width 0.1)
				(type default)
			)
			(layer "F.Fab")
		)
		(pad "1" smd circle
			(at -0.40005 0 90)
			(size 0 0)
			(layers "F.Cu" "F.Mask" "F.Paste")
			(net "PWRGD_P3V3_AUX_PDB")
		)
		(pad "2" smd circle
			(at 0.40005 0 90)
			(size 0 0)
			(layers "F.Cu" "F.Mask" "F.Paste")
			(net "PWRGD_P3V3_AUX_PDB_R")
		)
	)
	(footprint ""
		(layer "F.Cu")
		(at 31.962852 -407.509218 180)
		(property "Reference" "R3432"
			(at 0 0 180)
			(layer "F.SilkS")
			(hide yes)
			(effects
				(font
					(size 1.27 1.27)
				)
			)
		)
		(property "Value" ""
			(at 0 0 180)
			(layer "F.Fab")
			(effects
				(font
					(size 1.27 1.27)
				)
			)
		)
		(duplicate_pad_numbers_are_jumpers no)
		(fp_line
			(start 0.7874 0.4064)
			(end -0.7874 0.4064)
			(stroke
				(width 0.1524)
				(type default)
			)
			(layer "F.SilkS")
		)
		(fp_line
			(start 0.7874 -0.4064)
			(end 0.7874 0.4064)
			(stroke
				(width 0.1524)
				(type default)
			)
			(layer "F.SilkS")
		)
		(fp_line
			(start -0.7874 0.4064)
			(end -0.7874 -0.4064)
			(stroke
				(width 0.1524)
				(type default)
			)
			(layer "F.SilkS")
		)
		(fp_line
			(start -0.7874 -0.4064)
			(end 0.7874 -0.4064)
			(stroke
				(width 0.1524)
				(type default)
			)
			(layer "F.SilkS")
		)
		(fp_line
			(start 0.67945 0.3048)
			(end 0.120396 0.3048)
			(stroke
				(width 0.1)
				(type default)
			)
			(layer "F.Fab")
		)
		(fp_line
			(start 0.67945 -0.3048)
			(end 0.67945 0.3048)
			(stroke
				(width 0.1)
				(type default)
			)
			(layer "F.Fab")
		)
		(fp_line
			(start 0.12065 -0.2794)
			(end 0.12065 -0.3048)
			(stroke
				(width 0.1)
				(type default)
			)
			(layer "F.Fab")
		)
		(fp_line
			(start 0.12065 -0.3048)
			(end 0.67945 -0.3048)
			(stroke
				(width 0.1)
				(type default)
			)
			(layer "F.Fab")
		)
		(fp_line
			(start 0.120396 0.3048)
			(end 0.120396 0.2794)
			(stroke
				(width 0.1)
				(type default)
			)
			(layer "F.Fab")
		)
		(fp_line
			(start 0.120396 0.2794)
			(end -0.12065 0.2794)
			(stroke
				(width 0.1)
				(type default)
			)
			(layer "F.Fab")
		)
		(fp_line
			(start -0.12065 0.3048)
			(end -0.67945 0.3048)
			(stroke
				(width 0.1)
				(type default)
			)
			(layer "F.Fab")
		)
		(fp_line
			(start -0.12065 0.2794)
			(end -0.12065 0.3048)
			(stroke
				(width 0.1)
				(type default)
			)
			(layer "F.Fab")
		)
		(fp_line
			(start -0.12065 -0.2794)
			(end 0.12065 -0.2794)
			(stroke
				(width 0.1)
				(type default)
			)
			(layer "F.Fab")
		)
		(fp_line
			(start -0.12065 -0.305054)
			(end -0.12065 -0.2794)
			(stroke
				(width 0.1)
				(type default)
			)
			(layer "F.Fab")
		)
		(fp_line
			(start -0.67945 0.3048)
			(end -0.67945 -0.305054)
			(stroke
				(width 0.1)
				(type default)
			)
			(layer "F.Fab")
		)
		(fp_line
			(start -0.67945 -0.305054)
			(end -0.12065 -0.305054)
			(stroke
				(width 0.1)
				(type default)
			)
			(layer "F.Fab")
		)
		(pad "1" smd circle
			(at -0.40005 0 180)
			(size 0 0)
			(layers "F.Cu" "F.Mask" "F.Paste")
			(net "P3V3_AUX")
		)
		(pad "2" smd circle
			(at 0.40005 0 180)
			(size 0 0)
			(layers "F.Cu" "F.Mask" "F.Paste")
			(net "GPU_FPGA_THERM_OVERT")
		)
	)
	(footprint ""
		(layer "F.Cu")
		(at 250.65482 -4.699 180)
		(property "Reference" "J67"
			(at -4.38785 -1.016 90)
			(unlocked yes)
			(layer "F.SilkS")
			(effects
				(font
					(size 0.7874 0.5842)
					(thickness 0.1524)
				)
				(justify left)
			)
		)
		(property "Value" ""
			(at 0 0 180)
			(layer "F.Fab")
			(effects
				(font
					(size 1.27 1.27)
				)
			)
		)
		(duplicate_pad_numbers_are_jumpers no)
		(fp_line
			(start 1.2192 2.1082)
			(end -1.2192 2.1082)
			(stroke
				(width 0.1524)
				(type default)
			)
			(layer "F.SilkS")
		)
		(fp_line
			(start 1.2192 -2.1082)
			(end 1.2192 2.1082)
			(stroke
				(width 0.1524)
				(type default)
			)
			(layer "F.SilkS")
		)
		(fp_line
			(start -1.2192 2.1082)
			(end -1.2192 -2.1082)
			(stroke
				(width 0.1524)
				(type default)
			)
			(layer "F.SilkS")
		)
		(fp_line
			(start -1.2192 -2.1082)
			(end 1.2192 -2.1082)
			(stroke
				(width 0.1524)
				(type default)
			)
			(layer "F.SilkS")
		)
		(pad "" np_thru_hole circle
			(at -2.8829 -1.27 90)
			(size 1.0414 1.0414)
			(drill 1.0414)
			(layers "*.Cu" "*.Mask")
			(clearance 0.381)
			(thermal_gap 0.381)
		)
		(pad "" np_thru_hole circle
			(at -2.8829 1.27 90)
			(size 1.0414 1.0414)
			(drill 1.0414)
			(layers "*.Cu" "*.Mask")
			(clearance 0.381)
			(thermal_gap 0.381)
		)
		(pad "" np_thru_hole circle
			(at 3.4671 -1.27 90)
			(size 1.0414 1.0414)
			(drill 1.0414)
			(layers "*.Cu" "*.Mask")
			(clearance 0.381)
			(thermal_gap 0.381)
		)
		(pad "" np_thru_hole circle
			(at 3.4671 1.27 90)
			(size 1.0414 1.0414)
			(drill 1.0414)
			(layers "*.Cu" "*.Mask")
			(clearance 0.381)
			(thermal_gap 0.381)
		)
		(pad "1" smd rect
			(at 0.8255 -0.249936 90)
			(size 0.3048 0.508)
			(layers "F.Cu" "F.Mask" "F.Paste")
			(net "DELTA_L_85_5INCH_IN3_DP")
		)
		(pad "2" smd rect
			(at 0.8255 0.249936 90)
			(size 0.3048 0.508)
			(layers "F.Cu" "F.Mask" "F.Paste")
			(net "DELTA_L_85_5INCH_IN3_DN")
		)
		(pad "3" smd circle
			(at 0 0 180)
			(size 0 0)
			(layers "F.Cu" "F.Mask" "F.Paste")
			(net "DELTA_L_GND_1")
		)
		(zone
			(layer "F.Cu")
			(hatch none 0.5)
			(connect_pads
				(clearance 0)
			)
			(min_thickness 0.25)
			(keepout
				(tracks not_allowed)
				(vias allowed)
				(pads allowed)
				(copperpour not_allowed)
				(footprints allowed)
			)
			(placement
				(enabled no)
				(sheetname "")
			)
			(fill
				(thermal_gap 0.5)
				(thermal_bridge_width 0.5)
				(island_removal_mode 0)
			)
			(polygon
				(pts
					(xy 249.53722 -4.15036) (xy 249.53722 -4.245864) (xy 250.13412 -4.245864) (xy 250.13412 -4.652264)
					(xy 249.53722 -4.652264) (xy 249.53722 -4.745736) (xy 250.13412 -4.745736) (xy 250.13412 -5.152136)
					(xy 249.53722 -5.152136) (xy 249.53722 -5.24764) (xy 250.23572 -5.24764) (xy 250.23572 -4.15036)
				)
			)
		)
		(zone
			(layers "F.Cu" "B.Cu" "In1.Cu" "In2.Cu" "In3.Cu" "In4.Cu" "In5.Cu" "In6.Cu"
				"In7.Cu" "In8.Cu" "In9.Cu" "In10.Cu" "In11.Cu" "In12.Cu" "In13.Cu" "In14.Cu"
				"In15.Cu" "In16.Cu"
			)
			(hatch none 0.5)
			(connect_pads
				(clearance 0)
			)
			(min_thickness 0.25)
			(keepout
				(tracks not_allowed)
				(vias allowed)
				(pads allowed)
				(copperpour not_allowed)
				(footprints allowed)
			)
			(placement
				(enabled no)
				(sheetname "")
			)
			(fill
				(thermal_gap 0.5)
				(thermal_bridge_width 0.5)
				(island_removal_mode 0)
			)
			(polygon
				(pts
					(arc
						(start 248.11482 -5.969)
						(mid 246.26062 -5.969)
						(end 248.11482 -5.969)
					)
				)
			)
		)
		(zone
			(layers "F.Cu" "B.Cu" "In1.Cu" "In2.Cu" "In3.Cu" "In4.Cu" "In5.Cu" "In6.Cu"
				"In7.Cu" "In8.Cu" "In9.Cu" "In10.Cu" "In11.Cu" "In12.Cu" "In13.Cu" "In14.Cu"
				"In15.Cu" "In16.Cu"
			)
			(hatch none 0.5)
			(connect_pads
				(clearance 0)
			)
			(min_thickness 0.25)
			(keepout
				(tracks not_allowed)
				(vias allowed)
				(pads allowed)
				(copperpour not_allowed)
				(footprints allowed)
			)
			(placement
				(enabled no)
				(sheetname "")
			)
			(fill
				(thermal_gap 0.5)
				(thermal_bridge_width 0.5)
				(island_removal_mode 0)
			)
			(polygon
				(pts
					(arc
						(start 248.11482 -3.429)
						(mid 246.26062 -3.429)
						(end 248.11482 -3.429)
					)
				)
			)
		)
		(zone
			(layers "F.Cu" "B.Cu" "In1.Cu" "In2.Cu" "In3.Cu" "In4.Cu" "In5.Cu" "In6.Cu"
				"In7.Cu" "In8.Cu" "In9.Cu" "In10.Cu" "In11.Cu" "In12.Cu" "In13.Cu" "In14.Cu"
				"In15.Cu" "In16.Cu"
			)
			(hatch none 0.5)
			(connect_pads
				(clearance 0)
			)
			(min_thickness 0.25)
			(keepout
				(tracks not_allowed)
				(vias allowed)
				(pads allowed)
				(copperpour not_allowed)
				(footprints allowed)
			)
			(placement
				(enabled no)
				(sheetname "")
			)
			(fill
				(thermal_gap 0.5)
				(thermal_bridge_width 0.5)
				(island_removal_mode 0)
			)
			(polygon
				(pts
					(arc
						(start 254.46482 -5.969)
						(mid 252.61062 -5.969)
						(end 254.46482 -5.969)
					)
				)
			)
		)
		(zone
			(layers "F.Cu" "B.Cu" "In1.Cu" "In2.Cu" "In3.Cu" "In4.Cu" "In5.Cu" "In6.Cu"
				"In7.Cu" "In8.Cu" "In9.Cu" "In10.Cu" "In11.Cu" "In12.Cu" "In13.Cu" "In14.Cu"
				"In15.Cu" "In16.Cu"
			)
			(hatch none 0.5)
			(connect_pads
				(clearance 0)
			)
			(min_thickness 0.25)
			(keepout
				(tracks not_allowed)
				(vias allowed)
				(pads allowed)
				(copperpour not_allowed)
				(footprints allowed)
			)
			(placement
				(enabled no)
				(sheetname "")
			)
			(fill
				(thermal_gap 0.5)
				(thermal_bridge_width 0.5)
				(island_removal_mode 0)
			)
			(polygon
				(pts
					(arc
						(start 254.46482 -3.429)
						(mid 252.61062 -3.429)
						(end 254.46482 -3.429)
					)
				)
			)
		)
	)
	(footprint ""
		(layer "F.Cu")
		(at 381.50165 -402.371052 -90)
		(property "Reference" "C940"
			(at 0 0 270)
			(layer "F.SilkS")
			(hide yes)
			(effects
				(font
					(size 1.27 1.27)
				)
			)
		)
		(property "Value" ""
			(at 0 0 270)
			(layer "F.Fab")
			(effects
				(font
					(size 1.27 1.27)
				)
			)
		)
		(duplicate_pad_numbers_are_jumpers no)
		(fp_line
			(start -0.299974 0.150114)
			(end -0.299974 -0.150114)
			(stroke
				(width 0.1)
				(type default)
			)
			(layer "F.Fab")
		)
		(fp_line
			(start 0.299974 0.150114)
			(end -0.299974 0.150114)
			(stroke
				(width 0.1)
				(type default)
			)
			(layer "F.Fab")
		)
		(fp_line
			(start -0.299974 -0.150114)
			(end 0.299974 -0.150114)
			(stroke
				(width 0.1)
				(type default)
			)
			(layer "F.Fab")
		)
		(fp_line
			(start 0.299974 -0.150114)
			(end 0.299974 0.150114)
			(stroke
				(width 0.1)
				(type default)
			)
			(layer "F.Fab")
		)
		(pad "1" smd rect
			(at -0.2667 0 270)
			(size 0.3048 0.381)
			(layers "F.Cu" "F.Mask" "F.Paste")
			(net "P5E_CPU0_PE2_TX_C_DN<12>")
		)
		(pad "2" smd rect
			(at 0.2667 0 270)
			(size 0.3048 0.381)
			(layers "F.Cu" "F.Mask" "F.Paste")
			(net "P5E_CPU0_PE2_TX_DN<12>")
		)
	)
)
